(kicad_pcb
	(version 20260206)
	(generator "pcbnew")
	(generator_version "10.0")
	(general
		(thickness 1.6)
		(legacy_teardrops no)
	)
	(paper "A4")
	(title_block
		(title "baseboard — 13948-1b.1110WZS1818.brd")
		(comment 1 "Honey Badger (Wiwynn) / footprints 1503-1510 of 2523")
	)
	(layers
		(0 "F.Cu" signal "TOP")
		(4 "In1.Cu" signal "L2GND")
		(6 "In2.Cu" signal "L3")
		(8 "In3.Cu" signal "L4VCC")
		(10 "In4.Cu" signal "L5VCC")
		(12 "In5.Cu" signal "L6")
		(14 "In6.Cu" signal "L7GND")
		(2 "B.Cu" signal "BOTTOM")
		(9 "F.Adhes" user "F.Adhesive")
		(11 "B.Adhes" user "B.Adhesive")
		(13 "F.Paste" user "Package Geometry/Pastemask Top")
		(15 "B.Paste" user "Package Geometry/Pastemask Bottom")
		(5 "F.SilkS" user "Ref Des/Silkscreen Top")
		(7 "B.SilkS" user "Ref Des/Silkscreen Bottom")
		(1 "F.Mask" user "Board Geometry/Soldermask Top")
		(3 "B.Mask" user "Board Geometry/Soldermask Bottom")
		(17 "Dwgs.User" user "User.Drawings")
		(19 "Cmts.User" user "User.Comments")
		(21 "Eco1.User" user "User.Eco1")
		(23 "Eco2.User" user "User.Eco2")
		(25 "Edge.Cuts" user "Board Geometry/Outline")
		(27 "Margin" user)
		(31 "F.CrtYd" user "Package Geometry/Place Bound Top")
		(29 "B.CrtYd" user "Package Geometry/Place Bound Bottom")
		(35 "F.Fab" user "Ref Des/Assembly Top")
		(33 "B.Fab" user "Ref Des/Assembly Bottom")
	)
	(footprint ""
		(layer "F.Cu")
		(at 201.295 -167.64 180)
		(property "Reference" "R580"
			(at 0 0 180)
			(layer "F.SilkS")
			(hide yes)
			(effects
				(font
					(size 1.27 1.27)
				)
			)
		)
		(property "Value" "4K7R2F-GP"
			(at 0.064008 -3.993896 180)
			(unlocked yes)
			(layer "F.Fab")
			(hide yes)
			(effects
				(font
					(size 1.016 1.016)
					(thickness 0.1524)
				)
			)
		)
		(property "Device Type" "R402H16"
			(at 0.064008 -5.517896 180)
			(unlocked yes)
			(layer "F.Fab")
			(hide yes)
			(effects
				(font
					(size 1.016 1.016)
					(thickness 0.1524)
				)
			)
		)
		(duplicate_pad_numbers_are_jumpers no)
		(fp_line
			(start 0.508 -0.9398)
			(end -0.508 -0.9398)
			(stroke
				(width 0.1524)
				(type default)
			)
			(layer "F.SilkS")
		)
		(fp_line
			(start -0.508 -0.9398)
			(end -0.508 0.9398)
			(stroke
				(width 0.1524)
				(type default)
			)
			(layer "F.SilkS")
		)
		(fp_rect
			(start -0.508 0.9398)
			(end 0.508 -0.9398)
			(stroke
				(width 0)
				(type default)
			)
			(fill no)
			(layer "F.CrtYd")
		)
		(fp_rect
			(start -0.508 0.9398)
			(end 0.508 -0.9398)
			(stroke
				(width 0)
				(type default)
			)
			(fill no)
			(layer "F.Fab")
		)
		(pad "1" smd custom
			(at 0 -0.4445 180)
			(size 0.1397 0.1397)
			(layers "F.Cu" "F.Mask" "F.Paste")
			(net "P3V3_B")
			(options
				(clearance outline)
				(anchor circle)
			)
			(primitives
				(gr_poly
					(pts
						(arc
							(start -0.1778 -0.2794)
							(mid -0.249642 -0.249642)
							(end -0.2794 -0.1778)
						)
						(arc
							(start -0.2794 0.1778)
							(mid -0.249642 0.249642)
							(end -0.1778 0.2794)
						)
						(arc
							(start 0.1778 0.2794)
							(mid 0.249642 0.249642)
							(end 0.2794 0.1778)
						)
						(arc
							(start 0.2794 -0.1778)
							(mid 0.249642 -0.249642)
							(end 0.1778 -0.2794)
						)
					)
					(width 0)
					(fill yes)
				)
			)
		)
		(pad "2" smd custom
			(at 0 0.4445 180)
			(size 0.1397 0.1397)
			(layers "F.Cu" "F.Mask" "F.Paste")
			(net "P3V3")
			(options
				(clearance outline)
				(anchor circle)
			)
			(primitives
				(gr_poly
					(pts
						(arc
							(start -0.1778 -0.2794)
							(mid -0.249642 -0.249642)
							(end -0.2794 -0.1778)
						)
						(arc
							(start -0.2794 0.1778)
							(mid -0.249642 0.249642)
							(end -0.1778 0.2794)
						)
						(arc
							(start 0.1778 0.2794)
							(mid 0.249642 0.249642)
							(end 0.2794 0.1778)
						)
						(arc
							(start 0.2794 -0.1778)
							(mid 0.249642 -0.249642)
							(end 0.1778 -0.2794)
						)
					)
					(width 0)
					(fill yes)
				)
			)
		)
	)
	(footprint ""
		(layer "F.Cu")
		(at 95.758 -4.191)
		(property "Reference" "SC1046"
			(at 0 0 0)
			(layer "F.SilkS")
			(hide yes)
			(effects
				(font
					(size 1.27 1.27)
				)
			)
		)
		(property "Value" "SCD1U16V2KX-3GP"
			(at 1.1811 -2.7051 0)
			(unlocked yes)
			(layer "F.Fab")
			(hide yes)
			(effects
				(font
					(size 1.016 1.016)
					(thickness 0.1524)
				)
			)
		)
		(property "Device Type" "C402H22"
			(at 1.1811 -4.2291 0)
			(unlocked yes)
			(layer "F.Fab")
			(hide yes)
			(effects
				(font
					(size 1.016 1.016)
					(thickness 0.1524)
				)
			)
		)
		(duplicate_pad_numbers_are_jumpers no)
		(fp_rect
			(start -0.4318 0.9525)
			(end 0.4318 -0.9525)
			(stroke
				(width 0)
				(type default)
			)
			(fill no)
			(layer "F.CrtYd")
		)
		(fp_rect
			(start -0.4318 0.9525)
			(end 0.4318 -0.9525)
			(stroke
				(width 0)
				(type default)
			)
			(fill no)
			(layer "F.Fab")
		)
		(pad "1" smd custom
			(at 0 -0.4445)
			(size 0.1524 0.1524)
			(layers "F.Cu" "F.Mask" "F.Paste")
			(net "P0V955_C")
			(options
				(clearance outline)
				(anchor circle)
			)
			(primitives
				(gr_poly
					(pts
						(arc
							(start 0.3048 -0.2032)
							(mid 0.275042 -0.275042)
							(end 0.2032 -0.3048)
						)
						(arc
							(start -0.2032 -0.3048)
							(mid -0.275042 -0.275042)
							(end -0.3048 -0.2032)
						)
						(arc
							(start -0.3048 0.2032)
							(mid -0.275042 0.275042)
							(end -0.2032 0.3048)
						)
						(arc
							(start 0.2032 0.3048)
							(mid 0.275042 0.275042)
							(end 0.3048 0.2032)
						)
					)
					(width 0)
					(fill yes)
				)
			)
		)
		(pad "2" smd custom
			(at 0 0.4445)
			(size 0.1524 0.1524)
			(layers "F.Cu" "F.Mask" "F.Paste")
			(net "GND")
			(options
				(clearance outline)
				(anchor circle)
			)
			(primitives
				(gr_poly
					(pts
						(arc
							(start 0.3048 -0.2032)
							(mid 0.275042 -0.275042)
							(end 0.2032 -0.3048)
						)
						(arc
							(start -0.2032 -0.3048)
							(mid -0.275042 -0.275042)
							(end -0.3048 -0.2032)
						)
						(arc
							(start -0.3048 0.2032)
							(mid -0.275042 0.275042)
							(end -0.2032 0.3048)
						)
						(arc
							(start 0.2032 0.3048)
							(mid 0.275042 0.275042)
							(end 0.3048 0.2032)
						)
					)
					(width 0)
					(fill yes)
				)
			)
		)
	)
	(footprint ""
		(layer "F.Cu")
		(at 289.687 -67.691 90)
		(property "Reference" "PR9003"
			(at 0 0 90)
			(layer "F.SilkS")
			(hide yes)
			(effects
				(font
					(size 1.27 1.27)
				)
			)
		)
		(property "Value" "0R2J-2-GP"
			(at 0.064008 -3.993896 90)
			(unlocked yes)
			(layer "F.Fab")
			(hide yes)
			(effects
				(font
					(size 1.016 1.016)
					(thickness 0.1524)
				)
			)
		)
		(property "Device Type" "R402H16"
			(at 0.064008 -5.517896 90)
			(unlocked yes)
			(layer "F.Fab")
			(hide yes)
			(effects
				(font
					(size 1.016 1.016)
					(thickness 0.1524)
				)
			)
		)
		(duplicate_pad_numbers_are_jumpers no)
		(fp_line
			(start 0.508 -0.9398)
			(end -0.508 -0.9398)
			(stroke
				(width 0.1524)
				(type default)
			)
			(layer "F.SilkS")
		)
		(fp_line
			(start -0.508 -0.9398)
			(end -0.508 0.9398)
			(stroke
				(width 0.1524)
				(type default)
			)
			(layer "F.SilkS")
		)
		(fp_rect
			(start -0.508 0.9398)
			(end 0.508 -0.9398)
			(stroke
				(width 0)
				(type default)
			)
			(fill no)
			(layer "F.CrtYd")
		)
		(fp_rect
			(start -0.508 0.9398)
			(end 0.508 -0.9398)
			(stroke
				(width 0)
				(type default)
			)
			(fill no)
			(layer "F.Fab")
		)
		(pad "1" smd custom
			(at 0 -0.4445 90)
			(size 0.1397 0.1397)
			(layers "F.Cu" "F.Mask" "F.Paste")
			(net "HSW_SDA1")
			(options
				(clearance outline)
				(anchor circle)
			)
			(primitives
				(gr_poly
					(pts
						(arc
							(start -0.1778 -0.2794)
							(mid -0.249642 -0.249642)
							(end -0.2794 -0.1778)
						)
						(arc
							(start -0.2794 0.1778)
							(mid -0.249642 0.249642)
							(end -0.1778 0.2794)
						)
						(arc
							(start 0.1778 0.2794)
							(mid 0.249642 0.249642)
							(end 0.2794 0.1778)
						)
						(arc
							(start 0.2794 -0.1778)
							(mid 0.249642 -0.249642)
							(end 0.1778 -0.2794)
						)
					)
					(width 0)
					(fill yes)
				)
			)
		)
		(pad "2" smd custom
			(at 0 0.4445 90)
			(size 0.1397 0.1397)
			(layers "F.Cu" "F.Mask" "F.Paste")
			(net "BMC_I2C_SDA_10")
			(options
				(clearance outline)
				(anchor circle)
			)
			(primitives
				(gr_poly
					(pts
						(arc
							(start -0.1778 -0.2794)
							(mid -0.249642 -0.249642)
							(end -0.2794 -0.1778)
						)
						(arc
							(start -0.2794 0.1778)
							(mid -0.249642 0.249642)
							(end -0.1778 0.2794)
						)
						(arc
							(start 0.1778 0.2794)
							(mid 0.249642 0.249642)
							(end 0.2794 0.1778)
						)
						(arc
							(start 0.2794 -0.1778)
							(mid 0.249642 -0.249642)
							(end 0.1778 -0.2794)
						)
					)
					(width 0)
					(fill yes)
				)
			)
		)
	)
	(footprint ""
		(layer "F.Cu")
		(at 327.406 -96.52 -90)
		(property "Reference" "PC39"
			(at 0 0 270)
			(layer "F.SilkS")
			(hide yes)
			(effects
				(font
					(size 1.27 1.27)
				)
			)
		)
		(property "Value" "SC100U6D3V6MX-GP"
			(at -0.0762 -5.1308 270)
			(unlocked yes)
			(layer "F.Fab")
			(hide yes)
			(effects
				(font
					(size 1.016 1.016)
					(thickness 0.1524)
				)
			)
		)
		(property "Device Type" "C1206H71"
			(at -0.127 -6.6548 270)
			(unlocked yes)
			(layer "F.Fab")
			(hide yes)
			(effects
				(font
					(size 1.016 1.016)
					(thickness 0.1524)
				)
			)
		)
		(duplicate_pad_numbers_are_jumpers no)
		(fp_line
			(start -1.016 2.2352)
			(end -1.016 0.8382)
			(stroke
				(width 0.1524)
				(type default)
			)
			(layer "F.SilkS")
		)
		(fp_line
			(start 1.016 2.2352)
			(end -1.016 2.2352)
			(stroke
				(width 0.1524)
				(type default)
			)
			(layer "F.SilkS")
		)
		(fp_line
			(start 1.016 0.8382)
			(end 1.016 2.2352)
			(stroke
				(width 0.1524)
				(type default)
			)
			(layer "F.SilkS")
		)
		(fp_line
			(start -1.016 -0.8382)
			(end -1.016 -2.2352)
			(stroke
				(width 0.1524)
				(type default)
			)
			(layer "F.SilkS")
		)
		(fp_line
			(start -1.016 -2.2352)
			(end 1.016 -2.2352)
			(stroke
				(width 0.1524)
				(type default)
			)
			(layer "F.SilkS")
		)
		(fp_line
			(start 1.016 -2.2352)
			(end 1.016 -0.8382)
			(stroke
				(width 0.1524)
				(type default)
			)
			(layer "F.SilkS")
		)
		(fp_rect
			(start -1.0922 2.3114)
			(end 1.0922 -2.3114)
			(stroke
				(width 0)
				(type default)
			)
			(fill no)
			(layer "F.CrtYd")
		)
		(fp_poly
			(pts
				(xy 1.0922 -2.3114) (xy 1.0922 2.3114) (xy -1.0922 2.3114) (xy -1.0922 -2.3114)
			)
			(stroke
				(width 0)
				(type default)
			)
			(fill no)
			(layer "F.Fab")
		)
		(pad "1" smd rect
			(at 0 -1.397 270)
			(size 1.651 1.27)
			(layers "F.Cu" "F.Mask" "F.Paste")
			(net "P3V3_STBY")
		)
		(pad "2" smd rect
			(at 0 1.397 270)
			(size 1.651 1.27)
			(layers "F.Cu" "F.Mask" "F.Paste")
			(net "GND")
		)
	)
	(footprint ""
		(layer "F.Cu")
		(at 267.2334 -45.6184 180)
		(property "Reference" "PR39"
			(at 0 0 180)
			(layer "F.SilkS")
			(hide yes)
			(effects
				(font
					(size 1.27 1.27)
				)
			)
		)
		(property "Value" "2D2R3J-2-GP"
			(at -0.0254 -2.5146 180)
			(unlocked yes)
			(layer "F.Fab")
			(hide yes)
			(effects
				(font
					(size 1.016 1.016)
					(thickness 0.1524)
				)
			)
		)
		(property "Device Type" "R603H22"
			(at -0.0254 -4.0386 180)
			(unlocked yes)
			(layer "F.Fab")
			(hide yes)
			(effects
				(font
					(size 1.016 1.016)
					(thickness 0.1524)
				)
			)
		)
		(duplicate_pad_numbers_are_jumpers no)
		(fp_line
			(start 0.2032 0)
			(end 0.4826 0)
			(stroke
				(width 0.2032)
				(type default)
			)
			(layer "F.SilkS")
		)
		(fp_line
			(start -0.4826 0)
			(end -0.2032 0)
			(stroke
				(width 0.2032)
				(type default)
			)
			(layer "F.SilkS")
		)
		(fp_rect
			(start -0.5842 1.3335)
			(end 0.5842 -1.3335)
			(stroke
				(width 0)
				(type default)
			)
			(fill no)
			(layer "F.CrtYd")
		)
		(fp_rect
			(start -0.5842 1.3335)
			(end 0.5842 -1.3335)
			(stroke
				(width 0)
				(type default)
			)
			(fill no)
			(layer "F.Fab")
		)
		(pad "1" smd custom
			(at 0 -0.762 180)
			(size 0.2159 0.2159)
			(layers "F.Cu" "F.Mask" "F.Paste")
			(net "P1V8_STBY_VDD")
			(options
				(clearance outline)
				(anchor circle)
			)
			(primitives
				(gr_poly
					(pts
						(arc
							(start -0.3302 -0.4318)
							(mid -0.402042 -0.402042)
							(end -0.4318 -0.3302)
						)
						(arc
							(start -0.4318 0.3302)
							(mid -0.402042 0.402042)
							(end -0.3302 0.4318)
						)
						(arc
							(start 0.3302 0.4318)
							(mid 0.402042 0.402042)
							(end 0.4318 0.3302)
						)
						(arc
							(start 0.4318 -0.3302)
							(mid 0.402042 -0.402042)
							(end 0.3302 -0.4318)
						)
					)
					(width 0)
					(fill yes)
				)
			)
		)
		(pad "2" smd custom
			(at 0 0.762 180)
			(size 0.2159 0.2159)
			(layers "F.Cu" "F.Mask" "F.Paste")
			(net "P12V")
			(options
				(clearance outline)
				(anchor circle)
			)
			(primitives
				(gr_poly
					(pts
						(arc
							(start -0.3302 -0.4318)
							(mid -0.402042 -0.402042)
							(end -0.4318 -0.3302)
						)
						(arc
							(start -0.4318 0.3302)
							(mid -0.402042 0.402042)
							(end -0.3302 0.4318)
						)
						(arc
							(start 0.3302 0.4318)
							(mid 0.402042 0.402042)
							(end 0.4318 0.3302)
						)
						(arc
							(start 0.4318 -0.3302)
							(mid 0.402042 -0.402042)
							(end 0.3302 -0.4318)
						)
					)
					(width 0)
					(fill yes)
				)
			)
		)
	)
	(footprint ""
		(layer "F.Cu")
		(at 271.804892 -192.934336)
		(property "Reference" "R333"
			(at 0 0 0)
			(layer "F.SilkS")
			(hide yes)
			(effects
				(font
					(size 1.27 1.27)
				)
			)
		)
		(property "Value" "47KR2F-GP"
			(at 0.064008 -3.993896 0)
			(unlocked yes)
			(layer "F.Fab")
			(hide yes)
			(effects
				(font
					(size 1.016 1.016)
					(thickness 0.1524)
				)
			)
		)
		(property "Device Type" "R402H16"
			(at 0.064008 -5.517896 0)
			(unlocked yes)
			(layer "F.Fab")
			(hide yes)
			(effects
				(font
					(size 1.016 1.016)
					(thickness 0.1524)
				)
			)
		)
		(duplicate_pad_numbers_are_jumpers no)
		(fp_line
			(start -0.508 -0.9398)
			(end -0.508 0.9398)
			(stroke
				(width 0.1524)
				(type default)
			)
			(layer "F.SilkS")
		)
		(fp_line
			(start 0.508 -0.9398)
			(end -0.508 -0.9398)
			(stroke
				(width 0.1524)
				(type default)
			)
			(layer "F.SilkS")
		)
		(fp_rect
			(start -0.508 0.9398)
			(end 0.508 -0.9398)
			(stroke
				(width 0)
				(type default)
			)
			(fill no)
			(layer "F.CrtYd")
		)
		(fp_rect
			(start -0.508 0.9398)
			(end 0.508 -0.9398)
			(stroke
				(width 0)
				(type default)
			)
			(fill no)
			(layer "F.Fab")
		)
		(pad "1" smd custom
			(at 0 -0.4445)
			(size 0.1397 0.1397)
			(layers "F.Cu" "F.Mask" "F.Paste")
			(net "P3V3_STBY")
			(options
				(clearance outline)
				(anchor circle)
			)
			(primitives
				(gr_poly
					(pts
						(arc
							(start -0.1778 -0.2794)
							(mid -0.249642 -0.249642)
							(end -0.2794 -0.1778)
						)
						(arc
							(start -0.2794 0.1778)
							(mid -0.249642 0.249642)
							(end -0.1778 0.2794)
						)
						(arc
							(start 0.1778 0.2794)
							(mid 0.249642 0.249642)
							(end 0.2794 0.1778)
						)
						(arc
							(start 0.2794 -0.1778)
							(mid 0.249642 -0.249642)
							(end 0.1778 -0.2794)
						)
					)
					(width 0)
					(fill yes)
				)
			)
		)
		(pad "2" smd custom
			(at 0 0.4445)
			(size 0.1397 0.1397)
			(layers "F.Cu" "F.Mask" "F.Paste")
			(net "FM_BMC_RESET_N")
			(options
				(clearance outline)
				(anchor circle)
			)
			(primitives
				(gr_poly
					(pts
						(arc
							(start -0.1778 -0.2794)
							(mid -0.249642 -0.249642)
							(end -0.2794 -0.1778)
						)
						(arc
							(start -0.2794 0.1778)
							(mid -0.249642 0.249642)
							(end -0.1778 0.2794)
						)
						(arc
							(start 0.1778 0.2794)
							(mid 0.249642 0.249642)
							(end 0.2794 0.1778)
						)
						(arc
							(start 0.2794 -0.1778)
							(mid 0.249642 -0.249642)
							(end 0.1778 -0.2794)
						)
					)
					(width 0)
					(fill yes)
				)
			)
		)
	)
	(footprint ""
		(layer "F.Cu")
		(at 199.898 -185.166)
		(property "Reference" "SC1310"
			(at 0 0 0)
			(layer "F.SilkS")
			(hide yes)
			(effects
				(font
					(size 1.27 1.27)
				)
			)
		)
		(property "Value" "SC10U6D3V5KX-4GP"
			(at -0.0762 -6.1214 0)
			(unlocked yes)
			(layer "F.Fab")
			(hide yes)
			(effects
				(font
					(size 1.016 1.016)
					(thickness 0.1524)
				)
			)
		)
		(property "Device Type" "C805H58"
			(at -0.0762 -8.1534 0)
			(unlocked yes)
			(layer "F.Fab")
			(hide yes)
			(effects
				(font
					(size 1.016 1.016)
					(thickness 0.1524)
				)
			)
		)
		(duplicate_pad_numbers_are_jumpers no)
		(fp_line
			(start 0.635 0)
			(end -0.635 0)
			(stroke
				(width 0.508)
				(type default)
			)
			(layer "F.SilkS")
		)
		(fp_rect
			(start -0.9652 1.778)
			(end 0.9652 -1.778)
			(stroke
				(width 0)
				(type default)
			)
			(fill no)
			(layer "F.CrtYd")
		)
		(fp_poly
			(pts
				(xy -0.9652 -1.778) (xy 0.9652 -1.778) (xy 0.9652 1.778) (xy -0.9652 1.778)
			)
			(stroke
				(width 0)
				(type default)
			)
			(fill no)
			(layer "F.Fab")
		)
		(pad "1" smd rect
			(at 0 -0.9652)
			(size 1.397 1.143)
			(layers "F.Cu" "F.Mask" "F.Paste")
			(net "HB_A_IN")
		)
		(pad "2" smd rect
			(at 0 0.9652)
			(size 1.397 1.143)
			(layers "F.Cu" "F.Mask" "F.Paste")
			(net "GND")
		)
	)
	(footprint ""
		(layer "F.Cu")
		(at 305.054 -160.655)
		(property "Reference" "R562"
			(at 0 0 0)
			(layer "F.SilkS")
			(hide yes)
			(effects
				(font
					(size 1.27 1.27)
				)
			)
		)
		(property "Value" "0R2J-2-GP"
			(at 0.064008 -3.993896 0)
			(unlocked yes)
			(layer "F.Fab")
			(hide yes)
			(effects
				(font
					(size 1.016 1.016)
					(thickness 0.1524)
				)
			)
		)
		(property "Device Type" "R402H16"
			(at 0.064008 -5.517896 0)
			(unlocked yes)
			(layer "F.Fab")
			(hide yes)
			(effects
				(font
					(size 1.016 1.016)
					(thickness 0.1524)
				)
			)
		)
		(duplicate_pad_numbers_are_jumpers no)
		(fp_line
			(start -0.508 -0.9398)
			(end -0.508 0.9398)
			(stroke
				(width 0.1524)
				(type default)
			)
			(layer "F.SilkS")
		)
		(fp_line
			(start 0.508 -0.9398)
			(end -0.508 -0.9398)
			(stroke
				(width 0.1524)
				(type default)
			)
			(layer "F.SilkS")
		)
		(fp_rect
			(start -0.508 0.9398)
			(end 0.508 -0.9398)
			(stroke
				(width 0)
				(type default)
			)
			(fill no)
			(layer "F.CrtYd")
		)
		(fp_rect
			(start -0.508 0.9398)
			(end 0.508 -0.9398)
			(stroke
				(width 0)
				(type default)
			)
			(fill no)
			(layer "F.Fab")
		)
		(pad "1" smd custom
			(at 0 -0.4445)
			(size 0.1397 0.1397)
			(layers "F.Cu" "F.Mask" "F.Paste")
			(net "BMC_JTAG_L_EN_R")
			(options
				(clearance outline)
				(anchor circle)
			)
			(primitives
				(gr_poly
					(pts
						(arc
							(start -0.1778 -0.2794)
							(mid -0.249642 -0.249642)
							(end -0.2794 -0.1778)
						)
						(arc
							(start -0.2794 0.1778)
							(mid -0.249642 0.249642)
							(end -0.1778 0.2794)
						)
						(arc
							(start 0.1778 0.2794)
							(mid 0.249642 0.249642)
							(end 0.2794 0.1778)
						)
						(arc
							(start 0.2794 -0.1778)
							(mid 0.249642 -0.249642)
							(end 0.1778 -0.2794)
						)
					)
					(width 0)
					(fill yes)
				)
			)
		)
		(pad "2" smd custom
			(at 0 0.4445)
			(size 0.1397 0.1397)
			(layers "F.Cu" "F.Mask" "F.Paste")
			(net "BMC_JTAG_L_EN")
			(options
				(clearance outline)
				(anchor circle)
			)
			(primitives
				(gr_poly
					(pts
						(arc
							(start -0.1778 -0.2794)
							(mid -0.249642 -0.249642)
							(end -0.2794 -0.1778)
						)
						(arc
							(start -0.2794 0.1778)
							(mid -0.249642 0.249642)
							(end -0.1778 0.2794)
						)
						(arc
							(start 0.1778 0.2794)
							(mid 0.249642 0.249642)
							(end 0.2794 0.1778)
						)
						(arc
							(start 0.2794 -0.1778)
							(mid 0.249642 -0.249642)
							(end 0.1778 -0.2794)
						)
					)
					(width 0)
					(fill yes)
				)
			)
		)
	)
)
